(kicad_pcb
	(version 20241229)
	(generator "pcbnew")
	(generator_version "9.0")
	(general
		(thickness 1.6296)
		(legacy_teardrops no)
	)
	(paper "A3")
	(title_block
		(title "Thunderbolt to 10GbE adapter")
		(date "2026-04-21")
		(rev "1.1.0")
		(company "Antmicro Ltd")
		(comment 1 "www.antmicro.com")
		(comment 9 "footprints 677-681 of 703")
	)
	(layers
		(0 "F.Cu" signal)
		(4 "In1.Cu" signal)
		(6 "In2.Cu" signal)
		(8 "In3.Cu" signal)
		(10 "In4.Cu" signal)
		(12 "In5.Cu" signal)
		(14 "In6.Cu" signal)
		(2 "B.Cu" signal)
		(9 "F.Adhes" user "F.Adhesive")
		(11 "B.Adhes" user "B.Adhesive")
		(13 "F.Paste" user)
		(15 "B.Paste" user)
		(5 "F.SilkS" user "F.Silkscreen")
		(7 "B.SilkS" user "B.Silkscreen")
		(1 "F.Mask" user)
		(3 "B.Mask" user)
		(17 "Dwgs.User" user "User.Drawings")
		(19 "Cmts.User" user "User.Comments")
		(21 "Eco1.User" user "User.Eco1")
		(23 "Eco2.User" user "User.Eco2")
		(25 "Edge.Cuts" user)
		(27 "Margin" user)
		(31 "F.CrtYd" user "F.Courtyard")
		(29 "B.CrtYd" user "B.Courtyard")
		(35 "F.Fab" user)
		(33 "B.Fab" user)
	)
	(footprint "antmicro-footprints:C_0402_1005Metric"
		(layer "B.Cu")
		(at 152.381866 89.535117 -90)
		(descr "Capacitor SMD 0402")
		(tags "capacitor SMD 0402")
		(property "Reference" "C191"
			(at 10.264883 -18.868134 90)
			(layer "B.SilkS")
			(effects
				(font
					(size 0.7 0.7)
					(thickness 0.15)
				)
				(justify mirror)
			)
		)
		(property "Value" "C_1u_25V_0402"
			(at -1.022927 -2.155213 90)
			(layer "B.Fab")
			(effects
				(font
					(size 0.7 0.7)
					(thickness 0.15)
				)
				(justify left bottom mirror)
			)
		)
		(property "Datasheet" "https://www.murata.com/products/productdetail?partno=GRM155R61E105KE11%23"
			(at 0 0 90)
			(layer "B.Fab")
			(hide yes)
			(effects
				(font
					(size 1.27 1.27)
					(thickness 0.15)
				)
				(justify mirror)
			)
		)
		(property "Description" "SMD Multilayer Ceramic Capacitor, 1 µF, 25 V, 0402 [1005 Metric], ± 10%, X5R, GRM Series"
			(at 0 0 90)
			(layer "B.Fab")
			(hide yes)
			(effects
				(font
					(size 1.27 1.27)
					(thickness 0.15)
				)
				(justify mirror)
			)
		)
		(property "MPN" "GRM155R61E105KE11J"
			(at 0 0 270)
			(unlocked yes)
			(layer "B.Fab")
			(hide yes)
			(effects
				(font
					(size 1 1)
					(thickness 0.15)
				)
				(justify mirror)
			)
		)
		(property "Manufacturer" "Murata"
			(at 0 0 270)
			(unlocked yes)
			(layer "B.Fab")
			(hide yes)
			(effects
				(font
					(size 1 1)
					(thickness 0.15)
				)
				(justify mirror)
			)
		)
		(property "License" "Apache-2.0"
			(at 0 0 270)
			(unlocked yes)
			(layer "B.Fab")
			(hide yes)
			(effects
				(font
					(size 1 1)
					(thickness 0.15)
				)
				(justify mirror)
			)
		)
		(property "Author" "Antmicro"
			(at 0 0 270)
			(unlocked yes)
			(layer "B.Fab")
			(hide yes)
			(effects
				(font
					(size 1 1)
					(thickness 0.15)
				)
				(justify mirror)
			)
		)
		(property "Val" "1u"
			(at 0 0 270)
			(unlocked yes)
			(layer "B.Fab")
			(hide yes)
			(effects
				(font
					(size 1 1)
					(thickness 0.15)
				)
				(justify mirror)
			)
		)
		(property "Voltage" "25V"
			(at 0 0 270)
			(unlocked yes)
			(layer "B.Fab")
			(hide yes)
			(effects
				(font
					(size 1 1)
					(thickness 0.15)
				)
				(justify mirror)
			)
		)
		(property "Dielectric" "X5R"
			(at 0 0 270)
			(unlocked yes)
			(layer "B.Fab")
			(hide yes)
			(effects
				(font
					(size 1 1)
					(thickness 0.15)
				)
				(justify mirror)
			)
		)
		(sheetname "/X710-AT2 power/")
		(sheetfile "x710-at2-power.kicad_sch")
		(attr smd)
		(fp_rect
			(start -0.925 0.47)
			(end 0.925 -0.47)
			(stroke
				(width 0.05)
				(type default)
			)
			(fill no)
			(layer "B.CrtYd")
		)
		(fp_line
			(start -0.494 0.25)
			(end 0.504 0.25)
			(stroke
				(width 0.15)
				(type solid)
			)
			(layer "B.Fab")
		)
		(fp_line
			(start 0.504 0.25)
			(end 0.504 -0.248)
			(stroke
				(width 0.15)
				(type solid)
			)
			(layer "B.Fab")
		)
		(fp_line
			(start -0.494 -0.248)
			(end -0.494 0.25)
			(stroke
				(width 0.15)
				(type solid)
			)
			(layer "B.Fab")
		)
		(fp_line
			(start 0.504 -0.248)
			(end -0.494 -0.248)
			(stroke
				(width 0.15)
				(type solid)
			)
			(layer "B.Fab")
		)
		(fp_text user "License: Apache-2.0"
			(at -0.939 -5.799 90)
			(layer "B.Fab")
			(effects
				(font
					(size 0.7 0.7)
					(thickness 0.15)
				)
				(justify left bottom mirror)
			)
		)
		(fp_text user "${REFERENCE}"
			(at -0.939 -4.599 90)
			(layer "B.Fab")
			(effects
				(font
					(size 0.7 0.7)
					(thickness 0.15)
				)
				(justify left bottom mirror)
			)
		)
		(fp_text user "Author: Antmicro"
			(at -0.939 -3.399 90)
			(layer "B.Fab")
			(effects
				(font
					(size 0.7 0.7)
					(thickness 0.15)
				)
				(justify left bottom mirror)
			)
		)
		(pad "1" smd roundrect
			(at -0.48 0 270)
			(size 0.59 0.64)
			(layers "B.Cu" "B.Mask" "B.Paste")
			(roundrect_rratio 0.25)
			(net 23 "GND")
			(pintype "passive")
		)
		(pad "2" smd roundrect
			(at 0.48 0 270)
			(size 0.59 0.64)
			(layers "B.Cu" "B.Mask" "B.Paste")
			(roundrect_rratio 0.25)
			(net 18 "+1V88")
			(pintype "passive")
		)
	)
	(footprint "antmicro-footprints:C_0603_1608Metric"
		(layer "B.Cu")
		(at 150.231867 89.985117 -90)
		(descr "Capacitor SMD 0603")
		(tags "capacitor 0603")
		(property "Reference" "C167"
			(at 10.414883 -18.868134 90)
			(layer "B.SilkS")
			(effects
				(font
					(size 0.7 0.7)
					(thickness 0.15)
				)
				(justify mirror)
			)
		)
		(property "Value" "C_10u_10V_X7R_0603"
			(at -1.42757 -1.770288 90)
			(layer "B.Fab")
			(effects
				(font
					(size 0.7 0.7)
					(thickness 0.15)
				)
				(justify left bottom mirror)
			)
		)
		(property "Datasheet" "https://www.murata.com/products/productdetail?partno=GRM188Z71A106KA73%23"
			(at 0 0 90)
			(layer "B.Fab")
			(hide yes)
			(effects
				(font
					(size 1.27 1.27)
					(thickness 0.15)
				)
				(justify mirror)
			)
		)
		(property "Description" "SMD Multilayer Ceramic Capacitor,  10µF, 10V, 0603, ±10%, X7R"
			(at 0 0 90)
			(layer "B.Fab")
			(hide yes)
			(effects
				(font
					(size 1.27 1.27)
					(thickness 0.15)
				)
				(justify mirror)
			)
		)
		(property "MPN" "GRM188Z71A106KA73D"
			(at 0 0 270)
			(unlocked yes)
			(layer "B.Fab")
			(hide yes)
			(effects
				(font
					(size 1 1)
					(thickness 0.15)
				)
				(justify mirror)
			)
		)
		(property "Val" "10u"
			(at 0 0 270)
			(unlocked yes)
			(layer "B.Fab")
			(hide yes)
			(effects
				(font
					(size 1 1)
					(thickness 0.15)
				)
				(justify mirror)
			)
		)
		(property "Voltage" "10V"
			(at 0 0 270)
			(unlocked yes)
			(layer "B.Fab")
			(hide yes)
			(effects
				(font
					(size 1 1)
					(thickness 0.15)
				)
				(justify mirror)
			)
		)
		(property "Dielectric" "X7R"
			(at 0 0 270)
			(unlocked yes)
			(layer "B.Fab")
			(hide yes)
			(effects
				(font
					(size 1 1)
					(thickness 0.15)
				)
				(justify mirror)
			)
		)
		(property "Manufacturer" "Murata"
			(at 0 0 270)
			(unlocked yes)
			(layer "B.Fab")
			(hide yes)
			(effects
				(font
					(size 1 1)
					(thickness 0.15)
				)
				(justify mirror)
			)
		)
		(property "License" "Apache-2.0"
			(at 0 0 270)
			(unlocked yes)
			(layer "B.Fab")
			(hide yes)
			(effects
				(font
					(size 1 1)
					(thickness 0.15)
				)
				(justify mirror)
			)
		)
		(property "Author" "Antmicro"
			(at 0 0 270)
			(unlocked yes)
			(layer "B.Fab")
			(hide yes)
			(effects
				(font
					(size 1 1)
					(thickness 0.15)
				)
				(justify mirror)
			)
		)
		(sheetname "/X710-AT2 power/")
		(sheetfile "x710-at2-power.kicad_sch")
		(attr smd)
		(fp_line
			(start -0.15 0.4)
			(end 0.15 0.4)
			(stroke
				(width 0.15)
				(type solid)
			)
			(layer "B.SilkS")
		)
		(fp_line
			(start -0.15 -0.4)
			(end 0.15 -0.4)
			(stroke
				(width 0.15)
				(type solid)
			)
			(layer "B.SilkS")
		)
		(fp_rect
			(start -1.25 0.65)
			(end 1.25 -0.65)
			(stroke
				(width 0.05)
				(type solid)
			)
			(fill no)
			(layer "B.CrtYd")
		)
		(fp_rect
			(start -0.8 0.4)
			(end 0.8 -0.4)
			(stroke
				(width 0.15)
				(type solid)
			)
			(fill no)
			(layer "B.Fab")
		)
		(fp_text user "License: Apache-2.0"
			(at -1.682 -5.895 90)
			(layer "B.Fab")
			(effects
				(font
					(size 0.7 0.7)
					(thickness 0.15)
				)
				(justify left bottom mirror)
			)
		)
		(fp_text user "${REFERENCE}"
			(at -1.682 -3.895 90)
			(layer "B.Fab")
			(effects
				(font
					(size 0.7 0.7)
					(thickness 0.15)
				)
				(justify left bottom mirror)
			)
		)
		(fp_text user "Author: Antmicro"
			(at -1.682 -4.894 90)
			(layer "B.Fab")
			(effects
				(font
					(size 0.7 0.7)
					(thickness 0.15)
				)
				(justify left bottom mirror)
			)
		)
		(pad "1" smd roundrect
			(at -0.7 0 270)
			(size 0.8 1)
			(layers "B.Cu" "B.Mask" "B.Paste")
			(roundrect_rratio 0.2)
			(net 23 "GND")
			(pintype "passive")
		)
		(pad "2" smd roundrect
			(at 0.7 0 270)
			(size 0.8 1)
			(layers "B.Cu" "B.Mask" "B.Paste")
			(roundrect_rratio 0.2)
			(net 18 "+1V88")
			(pintype "passive")
		)
	)
	(footprint "antmicro-footprints:TP_SMD_0.75mm"
		(layer "B.Cu")
		(at 159.731866 64.435117 90)
		(property "Reference" "TP29"
			(at -0.164883 3.268134 180)
			(layer "B.SilkS")
			(effects
				(font
					(size 0.7 0.7)
					(thickness 0.15)
				)
				(justify left bottom mirror)
			)
		)
		(property "Value" "TP_0.75mm_SMD"
			(at 0 -1.2 270)
			(layer "B.Fab")
			(effects
				(font
					(size 0.7 0.7)
					(thickness 0.15)
				)
				(justify left bottom mirror)
			)
		)
		(property "Description" "SMT test point"
			(at 0 0 270)
			(layer "B.Fab")
			(hide yes)
			(effects
				(font
					(size 1.27 1.27)
					(thickness 0.15)
				)
				(justify mirror)
			)
		)
		(property "MPN" ""
			(at 0 0 90)
			(unlocked yes)
			(layer "B.Fab")
			(hide yes)
			(effects
				(font
					(size 1 1)
					(thickness 0.15)
				)
				(justify mirror)
			)
		)
		(property "Manufacturer" ""
			(at 0 0 90)
			(unlocked yes)
			(layer "B.Fab")
			(hide yes)
			(effects
				(font
					(size 1 1)
					(thickness 0.15)
				)
				(justify mirror)
			)
		)
		(property "Author" "Antmicro"
			(at 0 0 90)
			(unlocked yes)
			(layer "B.Fab")
			(hide yes)
			(effects
				(font
					(size 1 1)
					(thickness 0.15)
				)
				(justify mirror)
			)
		)
		(property "License" "Apache-2.0"
			(at 0 0 90)
			(unlocked yes)
			(layer "B.Fab")
			(hide yes)
			(effects
				(font
					(size 1 1)
					(thickness 0.15)
				)
				(justify mirror)
			)
		)
		(sheetname "/X710-AT2 Misc/")
		(sheetfile "x710-at2-mics.kicad_sch")
		(attr exclude_from_pos_files exclude_from_bom)
		(fp_circle
			(center 0 0)
			(end 0.475 0)
			(stroke
				(width 0.05)
				(type default)
			)
			(fill no)
			(layer "B.CrtYd")
		)
		(fp_text user "Author: Antmicro"
			(at -0.4 -3.901 270)
			(layer "B.Fab")
			(effects
				(font
					(size 0.7 0.7)
					(thickness 0.15)
				)
				(justify left bottom mirror)
			)
		)
		(fp_text user "License: Apache-2.0"
			(at -0.4 -5.101 270)
			(layer "B.Fab")
			(effects
				(font
					(size 0.7 0.7)
					(thickness 0.15)
				)
				(justify left bottom mirror)
			)
		)
		(fp_text user "${REFERENCE}"
			(at -0.4 -2.7 270)
			(layer "B.Fab")
			(effects
				(font
					(size 0.7 0.7)
					(thickness 0.15)
				)
				(justify left bottom mirror)
			)
		)
		(pad "1" smd circle
			(at 0 0 90)
			(size 0.75 0.75)
			(layers "B.Cu" "B.Mask")
			(net 137 "/X710-AT2 Misc/NCSI.RXD_1")
			(pinfunction "1")
			(pintype "passive")
		)
	)
	(footprint "antmicro-footprints:R_0402_1005Metric"
		(layer "B.Cu")
		(at 142.5 118.174998 180)
		(descr "Resistor SMD 0402")
		(tags "resistor SMD 0402")
		(property "Reference" "R36"
			(at -19.75 7.450001 0)
			(layer "B.SilkS")
			(effects
				(font
					(size 0.7 0.7)
					(thickness 0.15)
				)
				(justify mirror)
			)
		)
		(property "Value" "R_2k2_0402"
			(at -1.011843 -1.772047 0)
			(layer "B.Fab")
			(effects
				(font
					(size 0.7 0.7)
					(thickness 0.15)
				)
				(justify left bottom mirror)
			)
		)
		(property "Datasheet" "https://www.bourns.com/docs/product-datasheets/cr.pdf"
			(at 0 0 0)
			(layer "B.Fab")
			(hide yes)
			(effects
				(font
					(size 1.27 1.27)
					(thickness 0.15)
				)
				(justify mirror)
			)
		)
		(property "Description" "SMD Chip Resistor, 2.2 kohm, ± 1%, 62.5 mW, 0402 [1005 Metric], Thick Film, General Purpose"
			(at 0 0 0)
			(layer "B.Fab")
			(hide yes)
			(effects
				(font
					(size 1.27 1.27)
					(thickness 0.15)
				)
				(justify mirror)
			)
		)
		(property "MPN" "CR0402-FX-2201GLF"
			(at 0 0 180)
			(unlocked yes)
			(layer "B.Fab")
			(hide yes)
			(effects
				(font
					(size 1 1)
					(thickness 0.15)
				)
				(justify mirror)
			)
		)
		(property "Manufacturer" "Bourns"
			(at 0 0 180)
			(unlocked yes)
			(layer "B.Fab")
			(hide yes)
			(effects
				(font
					(size 1 1)
					(thickness 0.15)
				)
				(justify mirror)
			)
		)
		(property "License" "Apache-2.0"
			(at 0 0 180)
			(unlocked yes)
			(layer "B.Fab")
			(hide yes)
			(effects
				(font
					(size 1 1)
					(thickness 0.15)
				)
				(justify mirror)
			)
		)
		(property "Val" "2k2"
			(at 0 0 180)
			(unlocked yes)
			(layer "B.Fab")
			(hide yes)
			(effects
				(font
					(size 1 1)
					(thickness 0.15)
				)
				(justify mirror)
			)
		)
		(property "Tolerance" "1%"
			(at 0 0 180)
			(unlocked yes)
			(layer "B.Fab")
			(hide yes)
			(effects
				(font
					(size 1 1)
					(thickness 0.15)
				)
				(justify mirror)
			)
		)
		(property "Author" "Antmicro"
			(at 0 0 180)
			(unlocked yes)
			(layer "B.Fab")
			(hide yes)
			(effects
				(font
					(size 1 1)
					(thickness 0.15)
				)
				(justify mirror)
			)
		)
		(sheetname "/TB Controller/")
		(sheetfile "tb.kicad_sch")
		(attr smd)
		(fp_rect
			(start -0.925 0.47)
			(end 0.925 -0.47)
			(stroke
				(width 0.05)
				(type default)
			)
			(fill no)
			(layer "B.CrtYd")
		)
		(fp_rect
			(start -0.5 0.25)
			(end 0.5 -0.25)
			(stroke
				(width 0.15)
				(type solid)
			)
			(fill no)
			(layer "B.Fab")
		)
		(fp_text user "${REFERENCE}"
			(at -0.95 -3.168 0)
			(layer "B.Fab")
			(effects
				(font
					(size 0.7 0.7)
					(thickness 0.15)
				)
				(justify left bottom mirror)
			)
		)
		(fp_text user "License: Apache-2.0"
			(at -0.95 -5.169 0)
			(layer "B.Fab")
			(effects
				(font
					(size 0.7 0.7)
					(thickness 0.15)
				)
				(justify left bottom mirror)
			)
		)
		(fp_text user "Author: Antmicro"
			(at -0.95 -4.169 0)
			(layer "B.Fab")
			(effects
				(font
					(size 0.7 0.7)
					(thickness 0.15)
				)
				(justify left bottom mirror)
			)
		)
		(pad "1" smd roundrect
			(at -0.48 0 180)
			(size 0.59 0.64)
			(layers "B.Cu" "B.Mask" "B.Paste")
			(roundrect_rratio 0.25)
			(net 23 "GND")
			(pintype "passive")
		)
		(pad "2" smd roundrect
			(at 0.48 0 180)
			(size 0.59 0.64)
			(layers "B.Cu" "B.Mask" "B.Paste")
			(roundrect_rratio 0.25)
			(net 219 "Net-(U4C-DPSNK0_DDC_DATA)")
			(pintype "passive")
		)
	)
	(footprint "antmicro-footprints:R_0402_1005Metric"
		(layer "B.Cu")
		(at 154.231866 91.535117 -90)
		(descr "Resistor SMD 0402")
		(tags "resistor SMD 0402")
		(property "Reference" "R181"
			(at 10.864883 -18.868134 90)
			(layer "B.SilkS")
			(effects
				(font
					(size 0.7 0.7)
					(thickness 0.15)
				)
				(justify mirror)
			)
		)
		(property "Value" "R_1k_0402"
			(at -1.011843 -1.772047 90)
			(layer "B.Fab")
			(effects
				(font
					(size 0.7 0.7)
					(thickness 0.15)
				)
				(justify left bottom mirror)
			)
		)
		(property "Datasheet" "https://www.bourns.com/docs/product-datasheets/cr.pdf"
			(at 0 0 90)
			(layer "B.Fab")
			(hide yes)
			(effects
				(font
					(size 1.27 1.27)
					(thickness 0.15)
				)
				(justify mirror)
			)
		)
		(property "Description" "SMD Chip Resistor, 1 kohm, ± 1%, 63 mW, 0402 [1005 Metric], Thick Film, General Purpose"
			(at 0 0 90)
			(layer "B.Fab")
			(hide yes)
			(effects
				(font
					(size 1.27 1.27)
					(thickness 0.15)
				)
				(justify mirror)
			)
		)
		(property "MPN" "CR0402-FX-1001GLF"
			(at 0 0 270)
			(unlocked yes)
			(layer "B.Fab")
			(hide yes)
			(effects
				(font
					(size 1 1)
					(thickness 0.15)
				)
				(justify mirror)
			)
		)
		(property "Manufacturer" "Bourns"
			(at 0 0 270)
			(unlocked yes)
			(layer "B.Fab")
			(hide yes)
			(effects
				(font
					(size 1 1)
					(thickness 0.15)
				)
				(justify mirror)
			)
		)
		(property "License" "Apache-2.0"
			(at 0 0 270)
			(unlocked yes)
			(layer "B.Fab")
			(hide yes)
			(effects
				(font
					(size 1 1)
					(thickness 0.15)
				)
				(justify mirror)
			)
		)
		(property "Author" "Antmicro"
			(at 0 0 270)
			(unlocked yes)
			(layer "B.Fab")
			(hide yes)
			(effects
				(font
					(size 1 1)
					(thickness 0.15)
				)
				(justify mirror)
			)
		)
		(property "Val" "1k"
			(at 0 0 270)
			(unlocked yes)
			(layer "B.Fab")
			(hide yes)
			(effects
				(font
					(size 1 1)
					(thickness 0.15)
				)
				(justify mirror)
			)
		)
		(property "Tolerance" "1%"
			(at 0 0 270)
			(unlocked yes)
			(layer "B.Fab")
			(hide yes)
			(effects
				(font
					(size 1 1)
					(thickness 0.15)
				)
				(justify mirror)
			)
		)
		(sheetname "/X710-AT2 Misc/")
		(sheetfile "x710-at2-mics.kicad_sch")
		(attr smd)
		(fp_rect
			(start -0.925 0.47)
			(end 0.925 -0.47)
			(stroke
				(width 0.05)
				(type default)
			)
			(fill no)
			(layer "B.CrtYd")
		)
		(fp_rect
			(start -0.5 0.25)
			(end 0.5 -0.25)
			(stroke
				(width 0.15)
				(type solid)
			)
			(fill no)
			(layer "B.Fab")
		)
		(fp_text user "Author: Antmicro"
			(at -0.95 -4.169 90)
			(layer "B.Fab")
			(effects
				(font
					(size 0.7 0.7)
					(thickness 0.15)
				)
				(justify left bottom mirror)
			)
		)
		(fp_text user "License: Apache-2.0"
			(at -0.95 -5.169 90)
			(layer "B.Fab")
			(effects
				(font
					(size 0.7 0.7)
					(thickness 0.15)
				)
				(justify left bottom mirror)
			)
		)
		(fp_text user "${REFERENCE}"
			(at -0.95 -3.168 90)
			(layer "B.Fab")
			(effects
				(font
					(size 0.7 0.7)
					(thickness 0.15)
				)
				(justify left bottom mirror)
			)
		)
		(pad "1" smd roundrect
			(at -0.48 0 270)
			(size 0.59 0.64)
			(layers "B.Cu" "B.Mask" "B.Paste")
			(roundrect_rratio 0.25)
			(net 85 "/X710-AT2 Misc/RSVDK40_1P88V")
			(pintype "passive")
		)
		(pad "2" smd roundrect
			(at 0.48 0 270)
			(size 0.59 0.64)
			(layers "B.Cu" "B.Mask" "B.Paste")
			(roundrect_rratio 0.25)
			(net 18 "+1V88")
			(pintype "passive")
		)
	)
)
